# S9S_MB_2U (Grand Teton) — schematic netlist excerpt (pin names and nets, part order shuffled) for the footprints in the layout excerpt that follows; sources: Cadence DE-HDL packaged netlist, KiCad conversion of 03242023_DA0F0TMBIJ0_F0T_Motherboard_J_brd_V01_OCP.brd

C807  Q_CAP_DIFFBUS  DIFF BUS_0.22UF 6.3V 20% X6S  pkg C0201  page 175 : \1\ = P5E_CPU1_PE1_TX_C_DP<15> ; \2\ = P5E_CPU1_PE1_TX_DP<15>
R4750  Q_RES  49.9 1% CHIP  pkg 0402LF  page 158 : A = OCP_SFF_AUX_PWR_EN_R2 ; B = OCP_SFF_AUX_PWR_EN
R242  Q_RES  4.75K 1% CHIP  pkg 0402LF  page 121 : A = P3V3 ; B = H_CPU1_THERMTRIP_VT_N

(kicad_pcb
	(version 20260206)
	(generator "pcbnew")
	(generator_version "10.0")
	(general
		(thickness 1.6)
		(legacy_teardrops no)
	)
	(paper "A4")
	(title_block
		(title "03242023_DA0F0TMBIJ0_F0T_Motherboard_J_brd_V01_OCP.brd")
		(comment 1 "Grand Teton / footprints 3285-3287 of 6105")
	)
	(layers
		(0 "F.Cu" signal "TOP")
		(4 "In1.Cu" signal "GND")
		(6 "In2.Cu" signal "IN1")
		(8 "In3.Cu" signal "GND1")
		(10 "In4.Cu" signal "IN2")
		(12 "In5.Cu" signal "GND2")
		(14 "In6.Cu" signal "IN3")
		(16 "In7.Cu" signal "GND3")
		(18 "In8.Cu" signal "VCC")
		(20 "In9.Cu" signal "VCC1")
		(22 "In10.Cu" signal "GND4")
		(24 "In11.Cu" signal "IN4")
		(26 "In12.Cu" signal "GND5")
		(28 "In13.Cu" signal "IN5")
		(30 "In14.Cu" signal "GND6")
		(32 "In15.Cu" signal "IN6")
		(34 "In16.Cu" signal "GND7")
		(2 "B.Cu" signal "BOTTOM")
		(9 "F.Adhes" user "F.Adhesive")
		(11 "B.Adhes" user "B.Adhesive")
		(13 "F.Paste" user "Package Geometry/Pastemask Top")
		(15 "B.Paste" user "Package Geometry/Pastemask Bottom")
		(5 "F.SilkS" user "Ref Des/Silkscreen Top")
		(7 "B.SilkS" user "Ref Des/Silkscreen Bottom")
		(1 "F.Mask" user "Board Geometry/Soldermask Top")
		(3 "B.Mask" user "Board Geometry/Soldermask Bottom")
		(17 "Dwgs.User" user "User.Drawings")
		(19 "Cmts.User" user "User.Comments")
		(21 "Eco1.User" user "User.Eco1")
		(23 "Eco2.User" user "User.Eco2")
		(25 "Edge.Cuts" user "Board Geometry/Outline")
		(27 "Margin" user)
		(31 "F.CrtYd" user "Package Geometry/Place Bound Top")
		(29 "B.CrtYd" user "Package Geometry/Place Bound Bottom")
		(35 "F.Fab" user "Ref Des/Assembly Top")
		(33 "B.Fab" user "Ref Des/Assembly Bottom")
	)
	(footprint ""
		(layer "F.Cu")
		(at 440.50966 -106.38536 90)
		(property "Reference" "R4750"
			(at 0 0 90)
			(layer "F.SilkS")
			(hide yes)
			(effects
				(font
					(size 1.27 1.27)
				)
			)
		)
		(property "Value" ""
			(at 0 0 90)
			(layer "F.Fab")
			(effects
				(font
					(size 1.27 1.27)
				)
			)
		)
		(duplicate_pad_numbers_are_jumpers no)
		(fp_line
			(start 0.7874 -0.4064)
			(end 0.7874 0.4064)
			(stroke
				(width 0.1524)
				(type default)
			)
			(layer "F.SilkS")
		)
		(fp_line
			(start -0.7874 -0.4064)
			(end 0.7874 -0.4064)
			(stroke
				(width 0.1524)
				(type default)
			)
			(layer "F.SilkS")
		)
		(fp_line
			(start 0.7874 0.4064)
			(end -0.7874 0.4064)
			(stroke
				(width 0.1524)
				(type default)
			)
			(layer "F.SilkS")
		)
		(fp_line
			(start -0.7874 0.4064)
			(end -0.7874 -0.4064)
			(stroke
				(width 0.1524)
				(type default)
			)
			(layer "F.SilkS")
		)
		(fp_line
			(start -0.12065 -0.305054)
			(end -0.12065 -0.2794)
			(stroke
				(width 0.1)
				(type default)
			)
			(layer "F.Fab")
		)
		(fp_line
			(start -0.67945 -0.305054)
			(end -0.12065 -0.305054)
			(stroke
				(width 0.1)
				(type default)
			)
			(layer "F.Fab")
		)
		(fp_line
			(start 0.67945 -0.3048)
			(end 0.67945 0.3048)
			(stroke
				(width 0.1)
				(type default)
			)
			(layer "F.Fab")
		)
		(fp_line
			(start 0.12065 -0.3048)
			(end 0.67945 -0.3048)
			(stroke
				(width 0.1)
				(type default)
			)
			(layer "F.Fab")
		)
		(fp_line
			(start 0.12065 -0.2794)
			(end 0.12065 -0.3048)
			(stroke
				(width 0.1)
				(type default)
			)
			(layer "F.Fab")
		)
		(fp_line
			(start -0.12065 -0.2794)
			(end 0.12065 -0.2794)
			(stroke
				(width 0.1)
				(type default)
			)
			(layer "F.Fab")
		)
		(fp_line
			(start 0.120396 0.2794)
			(end -0.12065 0.2794)
			(stroke
				(width 0.1)
				(type default)
			)
			(layer "F.Fab")
		)
		(fp_line
			(start -0.12065 0.2794)
			(end -0.12065 0.3048)
			(stroke
				(width 0.1)
				(type default)
			)
			(layer "F.Fab")
		)
		(fp_line
			(start 0.67945 0.3048)
			(end 0.120396 0.3048)
			(stroke
				(width 0.1)
				(type default)
			)
			(layer "F.Fab")
		)
		(fp_line
			(start 0.120396 0.3048)
			(end 0.120396 0.2794)
			(stroke
				(width 0.1)
				(type default)
			)
			(layer "F.Fab")
		)
		(fp_line
			(start -0.12065 0.3048)
			(end -0.67945 0.3048)
			(stroke
				(width 0.1)
				(type default)
			)
			(layer "F.Fab")
		)
		(fp_line
			(start -0.67945 0.3048)
			(end -0.67945 -0.305054)
			(stroke
				(width 0.1)
				(type default)
			)
			(layer "F.Fab")
		)
		(pad "1" smd circle
			(at -0.40005 0 90)
			(size 0 0)
			(layers "F.Cu" "F.Mask" "F.Paste")
			(net "OCP_SFF_AUX_PWR_EN_R2")
		)
		(pad "2" smd circle
			(at 0.40005 0 90)
			(size 0 0)
			(layers "F.Cu" "F.Mask" "F.Paste")
			(net "OCP_SFF_AUX_PWR_EN")
		)
	)
	(footprint ""
		(layer "F.Cu")
		(at 15.508478 -16.099536 90)
		(property "Reference" "C807"
			(at 0 0 90)
			(layer "F.SilkS")
			(hide yes)
			(effects
				(font
					(size 1.27 1.27)
				)
			)
		)
		(property "Value" ""
			(at 0 0 90)
			(layer "F.Fab")
			(effects
				(font
					(size 1.27 1.27)
				)
			)
		)
		(duplicate_pad_numbers_are_jumpers no)
		(fp_line
			(start 0.299974 -0.150114)
			(end 0.299974 0.150114)
			(stroke
				(width 0.1)
				(type default)
			)
			(layer "F.Fab")
		)
		(fp_line
			(start -0.299974 -0.150114)
			(end 0.299974 -0.150114)
			(stroke
				(width 0.1)
				(type default)
			)
			(layer "F.Fab")
		)
		(fp_line
			(start 0.299974 0.150114)
			(end -0.299974 0.150114)
			(stroke
				(width 0.1)
				(type default)
			)
			(layer "F.Fab")
		)
		(fp_line
			(start -0.299974 0.150114)
			(end -0.299974 -0.150114)
			(stroke
				(width 0.1)
				(type default)
			)
			(layer "F.Fab")
		)
		(pad "1" smd rect
			(at -0.2667 0 90)
			(size 0.3048 0.381)
			(layers "F.Cu" "F.Mask" "F.Paste")
			(net "P5E_CPU1_PE1_TX_C_DP<15>")
		)
		(pad "2" smd rect
			(at 0.2667 0 90)
			(size 0.3048 0.381)
			(layers "F.Cu" "F.Mask" "F.Paste")
			(net "P5E_CPU1_PE1_TX_DP<15>")
		)
	)
	(footprint ""
		(layer "F.Cu")
		(at 127.69088 -92.674948 90)
		(property "Reference" "R242"
			(at 0 0 90)
			(layer "F.SilkS")
			(hide yes)
			(effects
				(font
					(size 1.27 1.27)
				)
			)
		)
		(property "Value" ""
			(at 0 0 90)
			(layer "F.Fab")
			(effects
				(font
					(size 1.27 1.27)
				)
			)
		)
		(duplicate_pad_numbers_are_jumpers no)
		(fp_line
			(start 0.7874 -0.4064)
			(end 0.7874 0.4064)
			(stroke
				(width 0.1524)
				(type default)
			)
			(layer "F.SilkS")
		)
		(fp_line
			(start -0.7874 -0.4064)
			(end 0.7874 -0.4064)
			(stroke
				(width 0.1524)
				(type default)
			)
			(layer "F.SilkS")
		)
		(fp_line
			(start 0.7874 0.4064)
			(end -0.7874 0.4064)
			(stroke
				(width 0.1524)
				(type default)
			)
			(layer "F.SilkS")
		)
		(fp_line
			(start -0.7874 0.4064)
			(end -0.7874 -0.4064)
			(stroke
				(width 0.1524)
				(type default)
			)
			(layer "F.SilkS")
		)
		(fp_line
			(start -0.12065 -0.305054)
			(end -0.12065 -0.2794)
			(stroke
				(width 0.1)
				(type default)
			)
			(layer "F.Fab")
		)
		(fp_line
			(start -0.67945 -0.305054)
			(end -0.12065 -0.305054)
			(stroke
				(width 0.1)
				(type default)
			)
			(layer "F.Fab")
		)
		(fp_line
			(start 0.67945 -0.3048)
			(end 0.67945 0.3048)
			(stroke
				(width 0.1)
				(type default)
			)
			(layer "F.Fab")
		)
		(fp_line
			(start 0.12065 -0.3048)
			(end 0.67945 -0.3048)
			(stroke
				(width 0.1)
				(type default)
			)
			(layer "F.Fab")
		)
		(fp_line
			(start 0.12065 -0.2794)
			(end 0.12065 -0.3048)
			(stroke
				(width 0.1)
				(type default)
			)
			(layer "F.Fab")
		)
		(fp_line
			(start -0.12065 -0.2794)
			(end 0.12065 -0.2794)
			(stroke
				(width 0.1)
				(type default)
			)
			(layer "F.Fab")
		)
		(fp_line
			(start 0.120396 0.2794)
			(end -0.12065 0.2794)
			(stroke
				(width 0.1)
				(type default)
			)
			(layer "F.Fab")
		)
		(fp_line
			(start -0.12065 0.2794)
			(end -0.12065 0.3048)
			(stroke
				(width 0.1)
				(type default)
			)
			(layer "F.Fab")
		)
		(fp_line
			(start 0.67945 0.3048)
			(end 0.120396 0.3048)
			(stroke
				(width 0.1)
				(type default)
			)
			(layer "F.Fab")
		)
		(fp_line
			(start 0.120396 0.3048)
			(end 0.120396 0.2794)
			(stroke
				(width 0.1)
				(type default)
			)
			(layer "F.Fab")
		)
		(fp_line
			(start -0.12065 0.3048)
			(end -0.67945 0.3048)
			(stroke
				(width 0.1)
				(type default)
			)
			(layer "F.Fab")
		)
		(fp_line
			(start -0.67945 0.3048)
			(end -0.67945 -0.305054)
			(stroke
				(width 0.1)
				(type default)
			)
			(layer "F.Fab")
		)
		(pad "1" smd circle
			(at -0.40005 0 90)
			(size 0 0)
			(layers "F.Cu" "F.Mask" "F.Paste")
			(net "P3V3")
		)
		(pad "2" smd circle
			(at 0.40005 0 90)
			(size 0 0)
			(layers "F.Cu" "F.Mask" "F.Paste")
			(net "H_CPU1_THERMTRIP_VT_N")
		)
	)
)
